# T6G (Grand Teton) — schematic netlist excerpt (pin names and nets, part order shuffled) for the footprints in the layout excerpt that follows; sources: Cadence DE-HDL packaged netlist, KiCad conversion of 04192023_DAF0TMB3IC0_F0TG_MB_C_brd_V02_OCP.brd

R193  Q_RES  0 5% CHIP  pkg 0402LF  page 81 : A = FM_CPU1_SMERR_N ; B = CPU1_SMERR_N
R982  Q_RES  4.7K 5% CHIP  pkg 0201LF  page 276 : A = TEST0_RT_CPU0_P0 ; B = GND
PR363  Q_RES  0 5% CHIP  pkg 0402LF  page 198 : A = PVDDCR_SOC_P0_VOS2 ; B = PVDDCR_SOC_P0

(kicad_pcb
	(version 20260206)
	(generator "pcbnew")
	(generator_version "10.0")
	(general
		(thickness 1.6)
		(legacy_teardrops no)
	)
	(paper "A4")
	(title_block
		(title "04192023_DAF0TMB3IC0_F0TG_MB_C_brd_V02_OCP.brd")
		(comment 1 "Grand Teton / footprints 7631-7633 of 8354")
	)
	(layers
		(0 "F.Cu" signal "TOP")
		(4 "In1.Cu" signal "GND")
		(6 "In2.Cu" signal "IN1")
		(8 "In3.Cu" signal "GND1")
		(10 "In4.Cu" signal "IN2")
		(12 "In5.Cu" signal "GND2")
		(14 "In6.Cu" signal "IN3")
		(16 "In7.Cu" signal "GND3")
		(18 "In8.Cu" signal "VCC")
		(20 "In9.Cu" signal "VCC1")
		(22 "In10.Cu" signal "GND4")
		(24 "In11.Cu" signal "IN4")
		(26 "In12.Cu" signal "GND5")
		(28 "In13.Cu" signal "IN5")
		(30 "In14.Cu" signal "GND6")
		(32 "In15.Cu" signal "IN6")
		(34 "In16.Cu" signal "GND7")
		(2 "B.Cu" signal "BOTTOM")
		(9 "F.Adhes" user "F.Adhesive")
		(11 "B.Adhes" user "B.Adhesive")
		(13 "F.Paste" user "Package Geometry/Pastemask Top")
		(15 "B.Paste" user "Package Geometry/Pastemask Bottom")
		(5 "F.SilkS" user "Ref Des/Silkscreen Top")
		(7 "B.SilkS" user "Ref Des/Silkscreen Bottom")
		(1 "F.Mask" user "Board Geometry/Soldermask Top")
		(3 "B.Mask" user "Board Geometry/Soldermask Bottom")
		(17 "Dwgs.User" user "User.Drawings")
		(19 "Cmts.User" user "User.Comments")
		(21 "Eco1.User" user "User.Eco1")
		(23 "Eco2.User" user "User.Eco2")
		(25 "Edge.Cuts" user "Board Geometry/Outline")
		(27 "Margin" user)
		(31 "F.CrtYd" user "Package Geometry/Place Bound Top")
		(29 "B.CrtYd" user "Package Geometry/Place Bound Bottom")
		(35 "F.Fab" user "Ref Des/Assembly Top")
		(33 "B.Fab" user "Ref Des/Assembly Bottom")
	)
	(footprint ""
		(layer "B.Cu")
		(at 409.809188 -165.928548 90)
		(property "Reference" "PR363"
			(at 0 0 90)
			(layer "B.SilkS")
			(hide yes)
			(effects
				(font
					(size 1.27 1.27)
				)
				(justify mirror)
			)
		)
		(property "Value" ""
			(at 0 0 90)
			(layer "B.Fab")
			(effects
				(font
					(size 1.27 1.27)
				)
				(justify mirror)
			)
		)
		(duplicate_pad_numbers_are_jumpers no)
		(fp_line
			(start 0.7874 -0.4064)
			(end -0.7874 -0.4064)
			(stroke
				(width 0.1524)
				(type default)
			)
			(layer "B.SilkS")
		)
		(fp_line
			(start -0.7874 -0.4064)
			(end -0.7874 0.4064)
			(stroke
				(width 0.1524)
				(type default)
			)
			(layer "B.SilkS")
		)
		(fp_line
			(start 0.7874 0.4064)
			(end 0.7874 -0.4064)
			(stroke
				(width 0.1524)
				(type default)
			)
			(layer "B.SilkS")
		)
		(fp_line
			(start -0.7874 0.4064)
			(end 0.7874 0.4064)
			(stroke
				(width 0.1524)
				(type default)
			)
			(layer "B.SilkS")
		)
		(fp_line
			(start 0.67945 -0.305054)
			(end 0.12065 -0.305054)
			(stroke
				(width 0.1)
				(type default)
			)
			(layer "B.Fab")
		)
		(fp_line
			(start 0.12065 -0.305054)
			(end 0.12065 -0.2794)
			(stroke
				(width 0.1)
				(type default)
			)
			(layer "B.Fab")
		)
		(fp_line
			(start -0.12065 -0.3048)
			(end -0.67945 -0.3048)
			(stroke
				(width 0.1)
				(type default)
			)
			(layer "B.Fab")
		)
		(fp_line
			(start -0.67945 -0.3048)
			(end -0.67945 0.3048)
			(stroke
				(width 0.1)
				(type default)
			)
			(layer "B.Fab")
		)
		(fp_line
			(start 0.12065 -0.2794)
			(end -0.12065 -0.2794)
			(stroke
				(width 0.1)
				(type default)
			)
			(layer "B.Fab")
		)
		(fp_line
			(start -0.12065 -0.2794)
			(end -0.12065 -0.3048)
			(stroke
				(width 0.1)
				(type default)
			)
			(layer "B.Fab")
		)
		(fp_line
			(start 0.12065 0.2794)
			(end 0.12065 0.3048)
			(stroke
				(width 0.1)
				(type default)
			)
			(layer "B.Fab")
		)
		(fp_line
			(start -0.120396 0.2794)
			(end 0.12065 0.2794)
			(stroke
				(width 0.1)
				(type default)
			)
			(layer "B.Fab")
		)
		(fp_line
			(start 0.67945 0.3048)
			(end 0.67945 -0.305054)
			(stroke
				(width 0.1)
				(type default)
			)
			(layer "B.Fab")
		)
		(fp_line
			(start 0.12065 0.3048)
			(end 0.67945 0.3048)
			(stroke
				(width 0.1)
				(type default)
			)
			(layer "B.Fab")
		)
		(fp_line
			(start -0.120396 0.3048)
			(end -0.120396 0.2794)
			(stroke
				(width 0.1)
				(type default)
			)
			(layer "B.Fab")
		)
		(fp_line
			(start -0.67945 0.3048)
			(end -0.120396 0.3048)
			(stroke
				(width 0.1)
				(type default)
			)
			(layer "B.Fab")
		)
		(pad "1" smd circle
			(at 0.40005 0 270)
			(size 0 0)
			(layers "B.Cu" "B.Mask" "B.Paste")
			(net "PVDDCR_SOC_P0_VOS2")
		)
		(pad "2" smd circle
			(at -0.40005 0 270)
			(size 0 0)
			(layers "B.Cu" "B.Mask" "B.Paste")
			(net "PVDDCR_SOC_P0")
		)
	)
	(footprint ""
		(layer "B.Cu")
		(at 187.35294 -130.468116 -90)
		(property "Reference" "R193"
			(at 0 0 90)
			(layer "B.SilkS")
			(hide yes)
			(effects
				(font
					(size 1.27 1.27)
				)
				(justify mirror)
			)
		)
		(property "Value" ""
			(at 0 0 90)
			(layer "B.Fab")
			(effects
				(font
					(size 1.27 1.27)
				)
				(justify mirror)
			)
		)
		(duplicate_pad_numbers_are_jumpers no)
		(fp_line
			(start -0.7874 0.4064)
			(end 0.7874 0.4064)
			(stroke
				(width 0.1524)
				(type default)
			)
			(layer "B.SilkS")
		)
		(fp_line
			(start 0.7874 0.4064)
			(end 0.7874 -0.4064)
			(stroke
				(width 0.1524)
				(type default)
			)
			(layer "B.SilkS")
		)
		(fp_line
			(start -0.7874 -0.4064)
			(end -0.7874 0.4064)
			(stroke
				(width 0.1524)
				(type default)
			)
			(layer "B.SilkS")
		)
		(fp_line
			(start 0.7874 -0.4064)
			(end -0.7874 -0.4064)
			(stroke
				(width 0.1524)
				(type default)
			)
			(layer "B.SilkS")
		)
		(fp_line
			(start -0.67945 0.3048)
			(end -0.120396 0.3048)
			(stroke
				(width 0.1)
				(type default)
			)
			(layer "B.Fab")
		)
		(fp_line
			(start -0.120396 0.3048)
			(end -0.120396 0.2794)
			(stroke
				(width 0.1)
				(type default)
			)
			(layer "B.Fab")
		)
		(fp_line
			(start 0.12065 0.3048)
			(end 0.67945 0.3048)
			(stroke
				(width 0.1)
				(type default)
			)
			(layer "B.Fab")
		)
		(fp_line
			(start 0.67945 0.3048)
			(end 0.67945 -0.305054)
			(stroke
				(width 0.1)
				(type default)
			)
			(layer "B.Fab")
		)
		(fp_line
			(start -0.120396 0.2794)
			(end 0.12065 0.2794)
			(stroke
				(width 0.1)
				(type default)
			)
			(layer "B.Fab")
		)
		(fp_line
			(start 0.12065 0.2794)
			(end 0.12065 0.3048)
			(stroke
				(width 0.1)
				(type default)
			)
			(layer "B.Fab")
		)
		(fp_line
			(start -0.12065 -0.2794)
			(end -0.12065 -0.3048)
			(stroke
				(width 0.1)
				(type default)
			)
			(layer "B.Fab")
		)
		(fp_line
			(start 0.12065 -0.2794)
			(end -0.12065 -0.2794)
			(stroke
				(width 0.1)
				(type default)
			)
			(layer "B.Fab")
		)
		(fp_line
			(start -0.67945 -0.3048)
			(end -0.67945 0.3048)
			(stroke
				(width 0.1)
				(type default)
			)
			(layer "B.Fab")
		)
		(fp_line
			(start -0.12065 -0.3048)
			(end -0.67945 -0.3048)
			(stroke
				(width 0.1)
				(type default)
			)
			(layer "B.Fab")
		)
		(fp_line
			(start 0.12065 -0.305054)
			(end 0.12065 -0.2794)
			(stroke
				(width 0.1)
				(type default)
			)
			(layer "B.Fab")
		)
		(fp_line
			(start 0.67945 -0.305054)
			(end 0.12065 -0.305054)
			(stroke
				(width 0.1)
				(type default)
			)
			(layer "B.Fab")
		)
		(pad "1" smd circle
			(at 0.40005 0 90)
			(size 0 0)
			(layers "B.Cu" "B.Mask" "B.Paste")
			(net "FM_CPU1_SMERR_N")
		)
		(pad "2" smd circle
			(at -0.40005 0 90)
			(size 0 0)
			(layers "B.Cu" "B.Mask" "B.Paste")
			(net "CPU1_SMERR_N")
		)
	)
	(footprint ""
		(layer "B.Cu")
		(at 299.265594 -394.29436 180)
		(property "Reference" "R982"
			(at 0 0 0)
			(layer "B.SilkS")
			(hide yes)
			(effects
				(font
					(size 1.27 1.27)
				)
				(justify mirror)
			)
		)
		(property "Value" ""
			(at 0 0 0)
			(layer "B.Fab")
			(effects
				(font
					(size 1.27 1.27)
				)
				(justify mirror)
			)
		)
		(duplicate_pad_numbers_are_jumpers no)
		(fp_line
			(start 0.32512 0.175006)
			(end 0.32512 -0.175006)
			(stroke
				(width 0.1)
				(type default)
			)
			(layer "B.Fab")
		)
		(fp_line
			(start 0.32512 -0.175006)
			(end -0.32512 -0.175006)
			(stroke
				(width 0.1)
				(type default)
			)
			(layer "B.Fab")
		)
		(fp_line
			(start -0.32512 0.175006)
			(end 0.32512 0.175006)
			(stroke
				(width 0.1)
				(type default)
			)
			(layer "B.Fab")
		)
		(fp_line
			(start -0.32512 -0.175006)
			(end -0.32512 0.175006)
			(stroke
				(width 0.1)
				(type default)
			)
			(layer "B.Fab")
		)
		(pad "1" smd rect
			(at 0.2667 0)
			(size 0.3048 0.381)
			(layers "B.Cu" "B.Mask" "B.Paste")
			(net "TEST0_RT_CPU0_P0")
		)
		(pad "2" smd rect
			(at -0.2667 0 180)
			(size 0.3048 0.381)
			(layers "B.Cu" "B.Mask" "B.Paste")
			(net "GND")
		)
	)
)
